%FSTAX25Y25*%
%MOIN*%
%SFA1B1*%

%IPPOS*%
%ADD12C,0.003940*%
%LNtimecard-dc-beta-v1-1*%
%LPD*%
G54D12*
X0177165Y0043012D02*
D01*
X0177147Y0043513*
X0177095Y0044011*
X0177007Y0044505*
X0176886Y0044992*
X0176731Y0045469*
X0176543Y0045934*
X0176323Y0046385*
X0176073Y0046819*
X0175792Y0047235*
X0175484Y004763*
X0175148Y0048003*
X0174787Y0048351*
X0174403Y0048673*
X0173997Y0048968*
X0173572Y0049234*
X0173129Y0049469*
X0172671Y0049673*
X01722Y0049845*
X0171718Y0049983*
X0171227Y0050087*
X0170731Y0050157*
X017023Y0050192*
X0169729*
X0169228Y0050157*
X0168732Y0050087*
X0168241Y0049983*
X0167759Y0049845*
X0167288Y0049673*
X016683Y0049469*
X0166387Y0049234*
X0165962Y0048968*
X0165556Y0048673*
X0165172Y0048351*
X0164811Y0048003*
X0164475Y004763*
X0164167Y0047235*
X0163886Y0046819*
X0163636Y0046385*
X0163416Y0045934*
X0163228Y0045469*
X0163073Y0044992*
X0162952Y0044505*
X0162864Y0044011*
X0162812Y0043513*
X0162795Y0043012*
X022874Y0029331D02*
D01*
X022873Y0029591*
X0228703Y0029851*
X0228658Y0030108*
X0228595Y0030361*
X0228514Y003061*
X0228416Y0030852*
X0228302Y0031086*
X0228171Y0031312*
X0228025Y0031529*
X0227865Y0031735*
X022769Y0031929*
X0227502Y003211*
X0227302Y0032278*
X0227091Y0032431*
X022687Y0032569*
X0226639Y0032692*
X0226401Y0032798*
X0226155Y0032887*
X0225904Y0032959*
X0225649Y0033014*
X022539Y003305*
X022513Y0033068*
X0224869*
X0224609Y003305*
X022435Y0033014*
X0224095Y0032959*
X0223844Y0032887*
X0223598Y0032798*
X022336Y0032692*
X022313Y0032569*
X0222908Y0032431*
X0222697Y0032278*
X0222497Y003211*
X0222309Y0031929*
X0222134Y0031735*
X0221974Y0031529*
X0221828Y0031312*
X0221697Y0031086*
X0221583Y0030852*
X0221485Y003061*
X0221404Y0030361*
X0221341Y0030108*
X0221296Y0029851*
X0221269Y0029591*
X022126Y0029331*
X022874D02*
D01*
X022873Y0029591*
X0228703Y0029851*
X0228658Y0030108*
X0228595Y0030361*
X0228514Y003061*
X0228416Y0030852*
X0228302Y0031086*
X0228171Y0031312*
X0228025Y0031529*
X0227865Y0031735*
X022769Y0031929*
X0227502Y003211*
X0227302Y0032278*
X0227091Y0032431*
X022687Y0032569*
X0226639Y0032692*
X0226401Y0032798*
X0226155Y0032887*
X0225904Y0032959*
X0225649Y0033014*
X022539Y003305*
X022513Y0033068*
X0224869*
X0224609Y003305*
X022435Y0033014*
X0224095Y0032959*
X0223844Y0032887*
X0223598Y0032798*
X022336Y0032692*
X022313Y0032569*
X0222908Y0032431*
X0222697Y0032278*
X0222497Y003211*
X0222309Y0031929*
X0222134Y0031735*
X0221974Y0031529*
X0221828Y0031312*
X0221697Y0031086*
X0221583Y0030852*
X0221485Y003061*
X0221404Y0030361*
X0221341Y0030108*
X0221296Y0029851*
X0221269Y0029591*
X022126Y0029331*
X0177165Y0043012D02*
D01*
X0177147Y0043513*
X0177095Y0044011*
X0177007Y0044505*
X0176886Y0044992*
X0176731Y0045469*
X0176543Y0045934*
X0176323Y0046385*
X0176073Y0046819*
X0175792Y0047235*
X0175484Y004763*
X0175148Y0048003*
X0174787Y0048351*
X0174403Y0048673*
X0173997Y0048968*
X0173572Y0049234*
X0173129Y0049469*
X0172671Y0049673*
X01722Y0049845*
X0171718Y0049983*
X0171227Y0050087*
X0170731Y0050157*
X017023Y0050192*
X0169729*
X0169228Y0050157*
X0168732Y0050087*
X0168241Y0049983*
X0167759Y0049845*
X0167288Y0049673*
X016683Y0049469*
X0166387Y0049234*
X0165962Y0048968*
X0165556Y0048673*
X0165172Y0048351*
X0164811Y0048003*
X0164475Y004763*
X0164167Y0047235*
X0163886Y0046819*
X0163636Y0046385*
X0163416Y0045934*
X0163228Y0045469*
X0163073Y0044992*
X0162952Y0044505*
X0162864Y0044011*
X0162812Y0043513*
X0162795Y0043012*
X0312205Y0050197D02*
X070876D01*
X0Y0437598D02*
X070876D01*
Y0050197*
X0Y0017717D02*
Y0437598D01*
Y0017717D02*
X0059055D01*
Y0050197*
X0131299*
Y0017717D02*
Y0050197D01*
Y0017717D02*
X0162795D01*
Y0043012*
X0177165Y0001969D02*
Y0043012D01*
X0179134Y0D02*
X0219291D01*
X0230709D02*
X0310236D01*
X0312205Y0001969D02*
Y0050197D01*
X0177165Y0001969D02*
X0179134Y0D01*
X0219291D02*
X022126Y0001969D01*
X022874D02*
X0230709Y0D01*
X0310236D02*
X0312205Y0001969D01*
X022126D02*
Y0029331D01*
X022874Y0001969D02*
Y0029331D01*
M02*